(kicad_pcb
	(version 20260206)
	(generator "pcbnew")
	(generator_version "10.0")
	(general
		(thickness 1.6)
		(legacy_teardrops no)
	)
	(paper "A4")
	(title_block
		(title "timecard-production-celestica-r4006 — R4006-B0001-02_R01.brd")
		(comment 1 "Time Appliance Project (Time Card) / footprints 525-529 of 1113")
	)
	(layers
		(0 "F.Cu" signal "TOP")
		(4 "In1.Cu" signal "L02_GND1")
		(6 "In2.Cu" signal "L03_SIG1")
		(8 "In3.Cu" signal "L04_GND2")
		(10 "In4.Cu" signal "L05_VCC1")
		(12 "In5.Cu" signal "L06_VCC2")
		(14 "In6.Cu" signal "L07_GND3")
		(16 "In7.Cu" signal "L08_SIG2")
		(18 "In8.Cu" signal "L09_GND4")
		(2 "B.Cu" signal "BOTTOM")
		(9 "F.Adhes" user "F.Adhesive")
		(11 "B.Adhes" user "B.Adhesive")
		(13 "F.Paste" user "Package Geometry/Pastemask Top")
		(15 "B.Paste" user "Package Geometry/Pastemask Bottom")
		(5 "F.SilkS" user "Ref Des/Silkscreen Top")
		(7 "B.SilkS" user "Ref Des/Silkscreen Bottom")
		(1 "F.Mask" user "Board Geometry/Soldermask Top")
		(3 "B.Mask" user "Board Geometry/Soldermask Bottom")
		(17 "Dwgs.User" user "User.Drawings")
		(19 "Cmts.User" user "User.Comments")
		(21 "Eco1.User" user "User.Eco1")
		(23 "Eco2.User" user "User.Eco2")
		(25 "Edge.Cuts" user "Board Geometry/Outline")
		(27 "Margin" user)
		(31 "F.CrtYd" user "Package Geometry/Place Bound Top")
		(29 "B.CrtYd" user "Package Geometry/Place Bound Bottom")
		(35 "F.Fab" user "Ref Des/Assembly Top")
		(33 "B.Fab" user "Ref Des/Assembly Bottom")
	)
	(footprint ""
		(layer "F.Cu")
		(at 11.2522 -16.9672 -90)
		(property "Reference" "R497"
			(at -0.0508 1.05283 90)
			(unlocked yes)
			(layer "F.SilkS")
			(effects
				(font
					(size 0.7874 0.5842)
					(thickness 0.1524)
				)
			)
		)
		(property "Value" "VAL*"
			(at 0.02032 2.13233 270)
			(unlocked yes)
			(layer "F.Fab")
			(hide yes)
			(effects
				(font
					(size 0.7874 0.5842)
					(thickness 0.1524)
				)
			)
		)
		(property "Tolerance" "TOL*"
			(at 0.044704 3.05435 270)
			(unlocked yes)
			(layer "Cmts.User")
			(hide yes)
			(effects
				(font
					(size 0.7874 0.5842)
					(thickness 0.1524)
				)
			)
		)
		(property "User Part Number" "PARTNUM*"
			(at 0.02032 4.024884 270)
			(unlocked yes)
			(layer "Cmts.User")
			(hide yes)
			(effects
				(font
					(size 0.7874 0.5842)
					(thickness 0.1524)
				)
			)
		)
		(property "Device Type" "RESISTOR-G155-11004-01,1MOHM,1%"
			(at 0.008382 1.210564 270)
			(unlocked yes)
			(layer "F.Fab")
			(hide yes)
			(effects
				(font
					(size 0.7874 0.5842)
					(thickness 0.1524)
				)
			)
		)
		(duplicate_pad_numbers_are_jumpers no)
		(fp_line
			(start -1.143 0.5588)
			(end 1.143 0.5588)
			(stroke
				(width 0.1)
				(type default)
			)
			(layer "F.SilkS")
		)
		(fp_line
			(start 1.143 0.5588)
			(end 1.143 -0.5588)
			(stroke
				(width 0.1)
				(type default)
			)
			(layer "F.SilkS")
		)
		(fp_line
			(start -1.143 -0.5588)
			(end -1.143 0.5588)
			(stroke
				(width 0.1)
				(type default)
			)
			(layer "F.SilkS")
		)
		(fp_line
			(start 1.143 -0.5588)
			(end -1.143 -0.5588)
			(stroke
				(width 0.1)
				(type default)
			)
			(layer "F.SilkS")
		)
		(fp_poly
			(pts
				(xy -1.143 0.5588) (xy 1.143 0.5588) (xy 1.143 -0.5588) (xy -1.143 -0.5588)
			)
			(stroke
				(width 0)
				(type default)
			)
			(fill no)
			(layer "F.CrtYd")
		)
		(fp_line
			(start -0.508 0.3048)
			(end 0.508 0.3048)
			(stroke
				(width 0.1)
				(type default)
			)
			(layer "F.Fab")
		)
		(fp_line
			(start 0.508 0.3048)
			(end 0.508 -0.3048)
			(stroke
				(width 0.1)
				(type default)
			)
			(layer "F.Fab")
		)
		(fp_line
			(start -0.508 -0.3048)
			(end -0.508 0.3048)
			(stroke
				(width 0.1)
				(type default)
			)
			(layer "F.Fab")
		)
		(fp_line
			(start 0.508 -0.3048)
			(end -0.508 -0.3048)
			(stroke
				(width 0.1)
				(type default)
			)
			(layer "F.Fab")
		)
		(pad "1" smd rect
			(at -0.5334 0 270)
			(size 0.7112 0.6096)
			(layers "F.Cu" "F.Mask" "F.Paste")
			(net "SG")
		)
		(pad "2" smd rect
			(at 0.5334 0 270)
			(size 0.7112 0.6096)
			(layers "F.Cu" "F.Mask" "F.Paste")
			(net "BF_SMA4_SIG_IO_CONN")
		)
		(zone
			(layer "F.Cu")
			(hatch none 0.5)
			(connect_pads
				(clearance 0)
			)
			(min_thickness 0.25)
			(keepout
				(tracks allowed)
				(vias not_allowed)
				(pads allowed)
				(copperpour not_allowed)
				(footprints allowed)
			)
			(placement
				(enabled no)
				(sheetname "")
			)
			(fill
				(thermal_gap 0.5)
				(thermal_bridge_width 0.5)
				(island_removal_mode 0)
			)
			(polygon
				(pts
					(xy 10.9474 -17.0434) (xy 10.9474 -16.891) (xy 11.557 -16.891) (xy 11.557 -17.0434)
				)
			)
		)
		(zone
			(layer "F.Cu")
			(hatch none 0.5)
			(connect_pads
				(clearance 0)
			)
			(min_thickness 0.25)
			(keepout
				(tracks not_allowed)
				(vias allowed)
				(pads allowed)
				(copperpour not_allowed)
				(footprints allowed)
			)
			(placement
				(enabled no)
				(sheetname "")
			)
			(fill
				(thermal_gap 0.5)
				(thermal_bridge_width 0.5)
				(island_removal_mode 0)
			)
			(polygon
				(pts
					(xy 10.9474 -17.0434) (xy 10.9474 -16.891) (xy 11.557 -16.891) (xy 11.557 -17.0434)
				)
			)
		)
	)
	(footprint ""
		(layer "F.Cu")
		(at 147.049998 -104.350058 -90)
		(property "Reference" "DS5"
			(at 0.464058 -1.452372 90)
			(unlocked yes)
			(layer "F.SilkS")
			(effects
				(font
					(size 0.7874 0.5842)
					(thickness 0.1524)
				)
			)
		)
		(property "Value" ""
			(at 0 0 270)
			(layer "F.Fab")
			(effects
				(font
					(size 1.27 1.27)
				)
			)
		)
		(property "Device Type" "OPTICAL-G170-10143-01"
			(at 0.1778 1.483081 270)
			(unlocked yes)
			(layer "F.Fab")
			(hide yes)
			(effects
				(font
					(size 0.786892 0.583946)
					(thickness 0.000001)
				)
			)
		)
		(property "User Part Number" "PARTNUM*"
			(at 0.1778 2.422881 270)
			(unlocked yes)
			(layer "Cmts.User")
			(hide yes)
			(effects
				(font
					(size 0.786892 0.583946)
					(thickness 0.000001)
				)
			)
		)
		(duplicate_pad_numbers_are_jumpers no)
		(fp_line
			(start -0.9398 1.3462)
			(end -2.2098 1.3462)
			(stroke
				(width 0.1)
				(type default)
			)
			(layer "F.SilkS")
		)
		(fp_line
			(start -1.5748 0.7112)
			(end -1.5748 1.9812)
			(stroke
				(width 0.1)
				(type default)
			)
			(layer "F.SilkS")
		)
		(fp_line
			(start -1.397508 0.704088)
			(end -1.397508 -0.704088)
			(stroke
				(width 0.1)
				(type default)
			)
			(layer "F.SilkS")
		)
		(fp_line
			(start 1.397508 0.704088)
			(end -1.397508 0.704088)
			(stroke
				(width 0.1)
				(type default)
			)
			(layer "F.SilkS")
		)
		(fp_line
			(start -1.397508 -0.704088)
			(end 1.397508 -0.704088)
			(stroke
				(width 0.1)
				(type default)
			)
			(layer "F.SilkS")
		)
		(fp_line
			(start 1.397508 -0.704088)
			(end 1.397508 0.704088)
			(stroke
				(width 0.1)
				(type default)
			)
			(layer "F.SilkS")
		)
		(fp_rect
			(start 1.905508 0.704088)
			(end 1.397508 -0.704088)
			(stroke
				(width 0)
				(type default)
			)
			(fill yes)
			(layer "F.SilkS")
		)
		(fp_rect
			(start 1.905508 0.958088)
			(end -1.651508 -0.958088)
			(stroke
				(width 0)
				(type default)
			)
			(fill no)
			(layer "F.CrtYd")
		)
		(fp_line
			(start -0.9398 0.9652)
			(end -2.2098 0.9652)
			(stroke
				(width 0.1)
				(type default)
			)
			(layer "F.Fab")
		)
		(fp_line
			(start -0.850138 0.450088)
			(end 0.850138 0.450088)
			(stroke
				(width 0.1)
				(type default)
			)
			(layer "F.Fab")
		)
		(fp_line
			(start 0.850138 0.450088)
			(end 0.850138 -0.450088)
			(stroke
				(width 0.1)
				(type default)
			)
			(layer "F.Fab")
		)
		(fp_line
			(start -1.5748 0.3302)
			(end -1.5748 1.6002)
			(stroke
				(width 0.1)
				(type default)
			)
			(layer "F.Fab")
		)
		(fp_line
			(start -0.850138 -0.450088)
			(end -0.850138 0.450088)
			(stroke
				(width 0.1)
				(type default)
			)
			(layer "F.Fab")
		)
		(fp_line
			(start 0.850138 -0.450088)
			(end -0.850138 -0.450088)
			(stroke
				(width 0.1)
				(type default)
			)
			(layer "F.Fab")
		)
		(fp_rect
			(start 0.850138 0.450088)
			(end 0.342138 -0.450088)
			(stroke
				(width 0)
				(type default)
			)
			(fill yes)
			(layer "F.Fab")
		)
		(fp_text user "C"
			(at 2.400808 -0.397002 0)
			(unlocked yes)
			(layer "F.SilkS")
			(effects
				(font
					(size 0.635 0.4064)
					(thickness 0.1524)
				)
			)
		)
		(fp_text user "A"
			(at -1.536192 -1.286002 0)
			(unlocked yes)
			(layer "F.SilkS")
			(effects
				(font
					(size 0.635 0.4064)
					(thickness 0.1524)
				)
			)
		)
		(fp_text user "C"
			(at 1.80467 0.0762 0)
			(unlocked yes)
			(layer "F.Fab")
			(effects
				(font
					(size 0.7874 0.5842)
					(thickness 0.1524)
				)
			)
		)
		(fp_text user "A"
			(at -1.528572 -0.651002 0)
			(unlocked yes)
			(layer "F.Fab")
			(effects
				(font
					(size 0.7874 0.5842)
					(thickness 0.1524)
				)
			)
		)
		(pad "A" smd rect
			(at -0.749808 0 270)
			(size 0.7874 0.7874)
			(layers "F.Cu" "F.Mask" "F.Paste")
			(net "UNNAMED_14_OPTICAL_I143_A")
		)
		(pad "C" smd rect
			(at 0.749808 0 270)
			(size 0.7874 0.7874)
			(layers "F.Cu" "F.Mask" "F.Paste")
			(net "SG")
		)
	)
	(footprint ""
		(layer "F.Cu")
		(at 36.9824 -100.2284 180)
		(property "Reference" "C29"
			(at 4.064 1.86563 0)
			(unlocked yes)
			(layer "F.SilkS")
			(effects
				(font
					(size 0.7874 0.5842)
					(thickness 0.1524)
				)
			)
		)
		(property "Value" "VAL*"
			(at 0.0762 2.067306 180)
			(unlocked yes)
			(layer "F.Fab")
			(hide yes)
			(effects
				(font
					(size 0.7874 0.5842)
					(thickness 0.1524)
				)
			)
		)
		(property "Device Type" "CAPACITOR-G105-0B104-CK,0.1UF,A"
			(at 0.0508 1.127506 180)
			(unlocked yes)
			(layer "F.Fab")
			(hide yes)
			(effects
				(font
					(size 0.7874 0.5842)
					(thickness 0.1524)
				)
			)
		)
		(property "User Part Number" "PARTNUM*"
			(at 0.1016 4.023106 180)
			(unlocked yes)
			(layer "Cmts.User")
			(hide yes)
			(effects
				(font
					(size 0.7874 0.5842)
					(thickness 0.1524)
				)
			)
		)
		(property "Tolerance" "TOL*"
			(at 0.0762 3.032506 180)
			(unlocked yes)
			(layer "Cmts.User")
			(hide yes)
			(effects
				(font
					(size 0.7874 0.5842)
					(thickness 0.1524)
				)
			)
		)
		(duplicate_pad_numbers_are_jumpers no)
		(fp_line
			(start 1.143 0.5588)
			(end 1.143 -0.5588)
			(stroke
				(width 0.1)
				(type default)
			)
			(layer "F.SilkS")
		)
		(fp_line
			(start 1.143 -0.5588)
			(end -1.143 -0.5588)
			(stroke
				(width 0.1)
				(type default)
			)
			(layer "F.SilkS")
		)
		(fp_line
			(start -1.143 0.5588)
			(end 1.143 0.5588)
			(stroke
				(width 0.1)
				(type default)
			)
			(layer "F.SilkS")
		)
		(fp_line
			(start -1.143 -0.5588)
			(end -1.143 0.5588)
			(stroke
				(width 0.1)
				(type default)
			)
			(layer "F.SilkS")
		)
		(fp_rect
			(start -1.143 0.5588)
			(end 1.143 -0.5588)
			(stroke
				(width 0)
				(type default)
			)
			(fill no)
			(layer "F.CrtYd")
		)
		(fp_line
			(start 0.508 0.3048)
			(end 0.508 -0.3048)
			(stroke
				(width 0.1)
				(type default)
			)
			(layer "F.Fab")
		)
		(fp_line
			(start 0.508 -0.3048)
			(end -0.508 -0.3048)
			(stroke
				(width 0.1)
				(type default)
			)
			(layer "F.Fab")
		)
		(fp_line
			(start -0.508 0.3048)
			(end 0.508 0.3048)
			(stroke
				(width 0.1)
				(type default)
			)
			(layer "F.Fab")
		)
		(fp_line
			(start -0.508 -0.3048)
			(end -0.508 0.3048)
			(stroke
				(width 0.1)
				(type default)
			)
			(layer "F.Fab")
		)
		(pad "1" smd rect
			(at -0.5334 0 180)
			(size 0.7112 0.6096)
			(layers "F.Cu" "F.Mask" "F.Paste")
			(net "R_XP5R0V_EN")
		)
		(pad "2" smd rect
			(at 0.5334 0 180)
			(size 0.7112 0.6096)
			(layers "F.Cu" "F.Mask" "F.Paste")
			(net "SG")
		)
		(zone
			(layer "F.Cu")
			(hatch none 0.5)
			(connect_pads
				(clearance 0)
			)
			(min_thickness 0.25)
			(keepout
				(tracks allowed)
				(vias not_allowed)
				(pads allowed)
				(copperpour not_allowed)
				(footprints allowed)
			)
			(placement
				(enabled no)
				(sheetname "")
			)
			(fill
				(thermal_gap 0.5)
				(thermal_bridge_width 0.5)
				(island_removal_mode 0)
			)
			(polygon
				(pts
					(xy 37.0586 -100.5332) (xy 36.9062 -100.5332) (xy 36.9062 -99.9236) (xy 37.0586 -99.9236)
				)
			)
		)
	)
	(footprint ""
		(layer "F.Cu")
		(at 95.758 -22.733 -90)
		(property "Reference" "R236"
			(at 2.794 0.08763 90)
			(unlocked yes)
			(layer "F.SilkS")
			(effects
				(font
					(size 0.7874 0.5842)
					(thickness 0.1524)
				)
			)
		)
		(property "Value" "VAL*"
			(at 0.02032 2.13233 270)
			(unlocked yes)
			(layer "F.Fab")
			(hide yes)
			(effects
				(font
					(size 0.7874 0.5842)
					(thickness 0.1524)
				)
			)
		)
		(property "Device Type" "RESISTOR-G155-14701-01,4.7KOHMA"
			(at 0.008382 1.210564 270)
			(unlocked yes)
			(layer "F.Fab")
			(hide yes)
			(effects
				(font
					(size 0.7874 0.5842)
					(thickness 0.1524)
				)
			)
		)
		(property "User Part Number" "PARTNUM*"
			(at 0.02032 4.024884 270)
			(unlocked yes)
			(layer "Cmts.User")
			(hide yes)
			(effects
				(font
					(size 0.7874 0.5842)
					(thickness 0.1524)
				)
			)
		)
		(property "Tolerance" "TOL*"
			(at 0.044704 3.05435 270)
			(unlocked yes)
			(layer "Cmts.User")
			(hide yes)
			(effects
				(font
					(size 0.7874 0.5842)
					(thickness 0.1524)
				)
			)
		)
		(duplicate_pad_numbers_are_jumpers no)
		(fp_line
			(start -1.143 0.5588)
			(end 1.143 0.5588)
			(stroke
				(width 0.1)
				(type default)
			)
			(layer "F.SilkS")
		)
		(fp_line
			(start 1.143 0.5588)
			(end 1.143 -0.5588)
			(stroke
				(width 0.1)
				(type default)
			)
			(layer "F.SilkS")
		)
		(fp_line
			(start -1.143 -0.5588)
			(end -1.143 0.5588)
			(stroke
				(width 0.1)
				(type default)
			)
			(layer "F.SilkS")
		)
		(fp_line
			(start 1.143 -0.5588)
			(end -1.143 -0.5588)
			(stroke
				(width 0.1)
				(type default)
			)
			(layer "F.SilkS")
		)
		(fp_rect
			(start 1.143 0.5588)
			(end -1.143 -0.5588)
			(stroke
				(width 0)
				(type default)
			)
			(fill no)
			(layer "F.CrtYd")
		)
		(fp_line
			(start -0.508 0.3048)
			(end 0.508 0.3048)
			(stroke
				(width 0.1)
				(type default)
			)
			(layer "F.Fab")
		)
		(fp_line
			(start 0.508 0.3048)
			(end 0.508 -0.3048)
			(stroke
				(width 0.1)
				(type default)
			)
			(layer "F.Fab")
		)
		(fp_line
			(start -0.508 -0.3048)
			(end -0.508 0.3048)
			(stroke
				(width 0.1)
				(type default)
			)
			(layer "F.Fab")
		)
		(fp_line
			(start 0.508 -0.3048)
			(end -0.508 -0.3048)
			(stroke
				(width 0.1)
				(type default)
			)
			(layer "F.Fab")
		)
		(pad "1" smd rect
			(at -0.5334 0 270)
			(size 0.7112 0.6096)
			(layers "F.Cu" "F.Mask" "F.Paste")
			(net "VDD3V3_OSC_125M")
		)
		(pad "2" smd rect
			(at 0.5334 0 270)
			(size 0.7112 0.6096)
			(layers "F.Cu" "F.Mask" "F.Paste")
			(net "CLK_125M_OE")
		)
		(zone
			(layer "F.Cu")
			(hatch none 0.5)
			(connect_pads
				(clearance 0)
			)
			(min_thickness 0.25)
			(keepout
				(tracks allowed)
				(vias not_allowed)
				(pads allowed)
				(copperpour not_allowed)
				(footprints allowed)
			)
			(placement
				(enabled no)
				(sheetname "")
			)
			(fill
				(thermal_gap 0.5)
				(thermal_bridge_width 0.5)
				(island_removal_mode 0)
			)
			(polygon
				(pts
					(xy 95.4532 -22.6568) (xy 96.0628 -22.6568) (xy 96.0628 -22.8092) (xy 95.4532 -22.8092)
				)
			)
		)
	)
	(footprint ""
		(layer "F.Cu")
		(at 18.161 -61.5442 90)
		(property "Reference" "C312"
			(at 0.1778 -0.97663 90)
			(unlocked yes)
			(layer "F.SilkS")
			(effects
				(font
					(size 0.7874 0.5842)
					(thickness 0.1524)
				)
			)
		)
		(property "Value" "VAL*"
			(at 0.0762 2.067306 90)
			(unlocked yes)
			(layer "F.Fab")
			(hide yes)
			(effects
				(font
					(size 0.7874 0.5842)
					(thickness 0.1524)
				)
			)
		)
		(property "Tolerance" "TOL*"
			(at 0.0762 3.032506 90)
			(unlocked yes)
			(layer "Cmts.User")
			(hide yes)
			(effects
				(font
					(size 0.7874 0.5842)
					(thickness 0.1524)
				)
			)
		)
		(property "User Part Number" "PARTNUM*"
			(at 0.1016 4.023106 90)
			(unlocked yes)
			(layer "Cmts.User")
			(hide yes)
			(effects
				(font
					(size 0.7874 0.5842)
					(thickness 0.1524)
				)
			)
		)
		(property "Device Type" "CAPACITOR-G105-0B104-CK,0.1UF,A"
			(at 0.0508 1.127506 90)
			(unlocked yes)
			(layer "F.Fab")
			(hide yes)
			(effects
				(font
					(size 0.7874 0.5842)
					(thickness 0.1524)
				)
			)
		)
		(duplicate_pad_numbers_are_jumpers no)
		(fp_line
			(start 1.143 -0.5588)
			(end -1.143 -0.5588)
			(stroke
				(width 0.1)
				(type default)
			)
			(layer "F.SilkS")
		)
		(fp_line
			(start -1.143 -0.5588)
			(end -1.143 0.5588)
			(stroke
				(width 0.1)
				(type default)
			)
			(layer "F.SilkS")
		)
		(fp_line
			(start 1.143 0.5588)
			(end 1.143 -0.5588)
			(stroke
				(width 0.1)
				(type default)
			)
			(layer "F.SilkS")
		)
		(fp_line
			(start -1.143 0.5588)
			(end 1.143 0.5588)
			(stroke
				(width 0.1)
				(type default)
			)
			(layer "F.SilkS")
		)
		(fp_poly
			(pts
				(xy -1.143 0.5588) (xy 1.143 0.5588) (xy 1.143 -0.5588) (xy -1.143 -0.5588)
			)
			(stroke
				(width 0)
				(type default)
			)
			(fill no)
			(layer "F.CrtYd")
		)
		(fp_line
			(start 0.508 -0.3048)
			(end -0.508 -0.3048)
			(stroke
				(width 0.1)
				(type default)
			)
			(layer "F.Fab")
		)
		(fp_line
			(start -0.508 -0.3048)
			(end -0.508 0.3048)
			(stroke
				(width 0.1)
				(type default)
			)
			(layer "F.Fab")
		)
		(fp_line
			(start 0.508 0.3048)
			(end 0.508 -0.3048)
			(stroke
				(width 0.1)
				(type default)
			)
			(layer "F.Fab")
		)
		(fp_line
			(start -0.508 0.3048)
			(end 0.508 0.3048)
			(stroke
				(width 0.1)
				(type default)
			)
			(layer "F.Fab")
		)
		(pad "1" smd rect
			(at -0.5334 0 90)
			(size 0.7112 0.6096)
			(layers "F.Cu" "F.Mask" "F.Paste")
			(net "XP3R3V")
		)
		(pad "2" smd rect
			(at 0.5334 0 90)
			(size 0.7112 0.6096)
			(layers "F.Cu" "F.Mask" "F.Paste")
			(net "SG")
		)
		(zone
			(layer "F.Cu")
			(hatch none 0.5)
			(connect_pads
				(clearance 0)
			)
			(min_thickness 0.25)
			(keepout
				(tracks not_allowed)
				(vias allowed)
				(pads allowed)
				(copperpour not_allowed)
				(footprints allowed)
			)
			(placement
				(enabled no)
				(sheetname "")
			)
			(fill
				(thermal_gap 0.5)
				(thermal_bridge_width 0.5)
				(island_removal_mode 0)
			)
			(polygon
				(pts
					(xy 18.4658 -61.468) (xy 18.4658 -61.6204) (xy 17.8562 -61.6204) (xy 17.8562 -61.468)
				)
			)
		)
		(zone
			(layer "F.Cu")
			(hatch none 0.5)
			(connect_pads
				(clearance 0)
			)
			(min_thickness 0.25)
			(keepout
				(tracks allowed)
				(vias not_allowed)
				(pads allowed)
				(copperpour not_allowed)
				(footprints allowed)
			)
			(placement
				(enabled no)
				(sheetname "")
			)
			(fill
				(thermal_gap 0.5)
				(thermal_bridge_width 0.5)
				(island_removal_mode 0)
			)
			(polygon
				(pts
					(xy 18.4658 -61.468) (xy 18.4658 -61.6204) (xy 17.8562 -61.6204) (xy 17.8562 -61.468)
				)
			)
		)
	)
)
